# SCM (Grand Teton) — schematic netlist excerpt (pin names and nets, part order shuffled) for the footprints in the layout excerpt that follows; sources: Cadence DE-HDL packaged netlist, KiCad conversion of 12092022_DA0F0TMDCD0_F0T_Management_Board_D_brd_V3_OCP.brd

C251  Q_CAP  0.1UF 25V 10% X7R  pkg 0402  page 52 : A = P3V3_RGM ; B = GND
R415  Q_RES  2.2 1% CHIP  pkg 0402LF  page 52 : A = SW_P3V3_AUX_BST_R ; B = SW_P3V3_AUX_BST

(kicad_pcb
	(version 20260206)
	(generator "pcbnew")
	(generator_version "10.0")
	(general
		(thickness 1.6)
		(legacy_teardrops no)
	)
	(paper "A4")
	(title_block
		(title "12092022_DA0F0TMDCD0_F0T_Management_Board_D_brd_V3_OCP.brd")
		(comment 1 "Grand Teton / footprints 379-380 of 1440")
	)
	(layers
		(0 "F.Cu" signal "TOP")
		(4 "In1.Cu" signal "GND")
		(6 "In2.Cu" signal "IN1")
		(8 "In3.Cu" signal "GND1")
		(10 "In4.Cu" signal "IN2")
		(12 "In5.Cu" signal "VCC")
		(14 "In6.Cu" signal "VCC1")
		(16 "In7.Cu" signal "IN3")
		(18 "In8.Cu" signal "GND2")
		(20 "In9.Cu" signal "IN4")
		(22 "In10.Cu" signal "GND3")
		(2 "B.Cu" signal "BOTTOM")
		(9 "F.Adhes" user "F.Adhesive")
		(11 "B.Adhes" user "B.Adhesive")
		(13 "F.Paste" user "Package Geometry/Pastemask Top")
		(15 "B.Paste" user "Package Geometry/Pastemask Bottom")
		(5 "F.SilkS" user "Ref Des/Silkscreen Top")
		(7 "B.SilkS" user "Ref Des/Silkscreen Bottom")
		(1 "F.Mask" user "Board Geometry/Soldermask Top")
		(3 "B.Mask" user "Board Geometry/Soldermask Bottom")
		(17 "Dwgs.User" user "User.Drawings")
		(19 "Cmts.User" user "User.Comments")
		(21 "Eco1.User" user "User.Eco1")
		(23 "Eco2.User" user "User.Eco2")
		(25 "Edge.Cuts" user "Board Geometry/Outline")
		(27 "Margin" user)
		(31 "F.CrtYd" user "Package Geometry/Place Bound Top")
		(29 "B.CrtYd" user "Package Geometry/Place Bound Bottom")
		(35 "F.Fab" user "Ref Des/Assembly Top")
		(33 "B.Fab" user "Ref Des/Assembly Bottom")
	)
	(footprint ""
		(layer "F.Cu")
		(at 9.2202 -67.183 180)
		(property "Reference" "R415"
			(at 0 0 180)
			(layer "F.SilkS")
			(hide yes)
			(effects
				(font
					(size 1.27 1.27)
				)
			)
		)
		(property "Value" ""
			(at 0 0 180)
			(layer "F.Fab")
			(effects
				(font
					(size 1.27 1.27)
				)
			)
		)
		(duplicate_pad_numbers_are_jumpers no)
		(fp_line
			(start 0.7874 0.4064)
			(end -0.7874 0.4064)
			(stroke
				(width 0.1524)
				(type default)
			)
			(layer "F.SilkS")
		)
		(fp_line
			(start 0.7874 -0.4064)
			(end 0.7874 0.4064)
			(stroke
				(width 0.1524)
				(type default)
			)
			(layer "F.SilkS")
		)
		(fp_line
			(start -0.7874 0.4064)
			(end -0.7874 -0.4064)
			(stroke
				(width 0.1524)
				(type default)
			)
			(layer "F.SilkS")
		)
		(fp_line
			(start -0.7874 -0.4064)
			(end 0.7874 -0.4064)
			(stroke
				(width 0.1524)
				(type default)
			)
			(layer "F.SilkS")
		)
		(fp_line
			(start 0.67945 0.3048)
			(end 0.120396 0.3048)
			(stroke
				(width 0.1)
				(type default)
			)
			(layer "F.Fab")
		)
		(fp_line
			(start 0.67945 -0.3048)
			(end 0.67945 0.3048)
			(stroke
				(width 0.1)
				(type default)
			)
			(layer "F.Fab")
		)
		(fp_line
			(start 0.12065 -0.2794)
			(end 0.12065 -0.3048)
			(stroke
				(width 0.1)
				(type default)
			)
			(layer "F.Fab")
		)
		(fp_line
			(start 0.12065 -0.3048)
			(end 0.67945 -0.3048)
			(stroke
				(width 0.1)
				(type default)
			)
			(layer "F.Fab")
		)
		(fp_line
			(start 0.120396 0.3048)
			(end 0.120396 0.2794)
			(stroke
				(width 0.1)
				(type default)
			)
			(layer "F.Fab")
		)
		(fp_line
			(start 0.120396 0.2794)
			(end -0.12065 0.2794)
			(stroke
				(width 0.1)
				(type default)
			)
			(layer "F.Fab")
		)
		(fp_line
			(start -0.12065 0.3048)
			(end -0.67945 0.3048)
			(stroke
				(width 0.1)
				(type default)
			)
			(layer "F.Fab")
		)
		(fp_line
			(start -0.12065 0.2794)
			(end -0.12065 0.3048)
			(stroke
				(width 0.1)
				(type default)
			)
			(layer "F.Fab")
		)
		(fp_line
			(start -0.12065 -0.2794)
			(end 0.12065 -0.2794)
			(stroke
				(width 0.1)
				(type default)
			)
			(layer "F.Fab")
		)
		(fp_line
			(start -0.12065 -0.305054)
			(end -0.12065 -0.2794)
			(stroke
				(width 0.1)
				(type default)
			)
			(layer "F.Fab")
		)
		(fp_line
			(start -0.67945 0.3048)
			(end -0.67945 -0.305054)
			(stroke
				(width 0.1)
				(type default)
			)
			(layer "F.Fab")
		)
		(fp_line
			(start -0.67945 -0.305054)
			(end -0.12065 -0.305054)
			(stroke
				(width 0.1)
				(type default)
			)
			(layer "F.Fab")
		)
		(pad "1" smd circle
			(at -0.40005 0 180)
			(size 0 0)
			(layers "F.Cu" "F.Mask" "F.Paste")
			(net "SW_P3V3_AUX_BST_R")
		)
		(pad "2" smd circle
			(at 0.40005 0 180)
			(size 0 0)
			(layers "F.Cu" "F.Mask" "F.Paste")
			(net "SW_P3V3_AUX_BST")
		)
	)
	(footprint ""
		(layer "F.Cu")
		(at 70.370446 -33.033716 90)
		(property "Reference" "C251"
			(at 0 0 90)
			(layer "F.SilkS")
			(hide yes)
			(effects
				(font
					(size 1.27 1.27)
				)
			)
		)
		(property "Value" ""
			(at 0 0 90)
			(layer "F.Fab")
			(effects
				(font
					(size 1.27 1.27)
				)
			)
		)
		(duplicate_pad_numbers_are_jumpers no)
		(fp_line
			(start 0.7874 -0.4064)
			(end 0.7874 0.4064)
			(stroke
				(width 0.1524)
				(type default)
			)
			(layer "F.SilkS")
		)
		(fp_line
			(start -0.7874 -0.4064)
			(end 0.7874 -0.4064)
			(stroke
				(width 0.1524)
				(type default)
			)
			(layer "F.SilkS")
		)
		(fp_line
			(start 0.7874 0.4064)
			(end -0.7874 0.4064)
			(stroke
				(width 0.1524)
				(type default)
			)
			(layer "F.SilkS")
		)
		(fp_line
			(start -0.7874 0.4064)
			(end -0.7874 -0.4064)
			(stroke
				(width 0.1524)
				(type default)
			)
			(layer "F.SilkS")
		)
		(fp_line
			(start -0.12065 -0.305054)
			(end -0.12065 -0.2794)
			(stroke
				(width 0.1)
				(type default)
			)
			(layer "F.Fab")
		)
		(fp_line
			(start -0.67945 -0.305054)
			(end -0.12065 -0.305054)
			(stroke
				(width 0.1)
				(type default)
			)
			(layer "F.Fab")
		)
		(fp_line
			(start 0.67945 -0.3048)
			(end 0.67945 0.3048)
			(stroke
				(width 0.1)
				(type default)
			)
			(layer "F.Fab")
		)
		(fp_line
			(start 0.12065 -0.3048)
			(end 0.67945 -0.3048)
			(stroke
				(width 0.1)
				(type default)
			)
			(layer "F.Fab")
		)
		(fp_line
			(start 0.12065 -0.2794)
			(end 0.12065 -0.3048)
			(stroke
				(width 0.1)
				(type default)
			)
			(layer "F.Fab")
		)
		(fp_line
			(start -0.12065 -0.2794)
			(end 0.12065 -0.2794)
			(stroke
				(width 0.1)
				(type default)
			)
			(layer "F.Fab")
		)
		(fp_line
			(start 0.120396 0.2794)
			(end -0.12065 0.2794)
			(stroke
				(width 0.1)
				(type default)
			)
			(layer "F.Fab")
		)
		(fp_line
			(start -0.12065 0.2794)
			(end -0.12065 0.3048)
			(stroke
				(width 0.1)
				(type default)
			)
			(layer "F.Fab")
		)
		(fp_line
			(start 0.67945 0.3048)
			(end 0.120396 0.3048)
			(stroke
				(width 0.1)
				(type default)
			)
			(layer "F.Fab")
		)
		(fp_line
			(start 0.120396 0.3048)
			(end 0.120396 0.2794)
			(stroke
				(width 0.1)
				(type default)
			)
			(layer "F.Fab")
		)
		(fp_line
			(start -0.12065 0.3048)
			(end -0.67945 0.3048)
			(stroke
				(width 0.1)
				(type default)
			)
			(layer "F.Fab")
		)
		(fp_line
			(start -0.67945 0.3048)
			(end -0.67945 -0.305054)
			(stroke
				(width 0.1)
				(type default)
			)
			(layer "F.Fab")
		)
		(pad "1" smd circle
			(at -0.40005 0 90)
			(size 0 0)
			(layers "F.Cu" "F.Mask" "F.Paste")
			(net "P3V3_RGM")
		)
		(pad "2" smd circle
			(at 0.40005 0 90)
			(size 0 0)
			(layers "F.Cu" "F.Mask" "F.Paste")
			(net "GND")
		)
	)
)
